# T6G (Grand Teton) — schematic netlist excerpt (pin names and nets, part order shuffled) for the footprints in the layout excerpt that follows; sources: Cadence DE-HDL packaged netlist, KiCad conversion of 04192023_DAF0TMB3IC0_F0TG_MB_C_brd_V02_OCP.brd

R3142  Q_RES  0 5% CHIP  pkg 0402LF  page 140 : A = HP_LVC3_OCP_V3_2_PRSNT2_N_R ; B = HP_LVC3_OCP_V3_2_PRSNT2_PLD_N
PC6600  Q_CAP  3300PF 50V 10% X7R  pkg 0402  page 364 : A = P0V9_RETIMER_CPU1_SENSE_R_P ; B = P0V9_RETIMER_CPU1_SENSE_SH_N
PC6581_2  Q_CAP  22UF 16V 20% X6S  pkg C0805  page 363 : A = SW_P12V_AUX_P0V9_RETIMER_CPU0_FLT ; B = GND

(kicad_pcb
	(version 20260206)
	(generator "pcbnew")
	(generator_version "10.0")
	(general
		(thickness 1.6)
		(legacy_teardrops no)
	)
	(paper "A4")
	(title_block
		(title "04192023_DAF0TMB3IC0_F0TG_MB_C_brd_V02_OCP.brd")
		(comment 1 "Grand Teton / footprints 4866-4868 of 8354")
	)
	(layers
		(0 "F.Cu" signal "TOP")
		(4 "In1.Cu" signal "GND")
		(6 "In2.Cu" signal "IN1")
		(8 "In3.Cu" signal "GND1")
		(10 "In4.Cu" signal "IN2")
		(12 "In5.Cu" signal "GND2")
		(14 "In6.Cu" signal "IN3")
		(16 "In7.Cu" signal "GND3")
		(18 "In8.Cu" signal "VCC")
		(20 "In9.Cu" signal "VCC1")
		(22 "In10.Cu" signal "GND4")
		(24 "In11.Cu" signal "IN4")
		(26 "In12.Cu" signal "GND5")
		(28 "In13.Cu" signal "IN5")
		(30 "In14.Cu" signal "GND6")
		(32 "In15.Cu" signal "IN6")
		(34 "In16.Cu" signal "GND7")
		(2 "B.Cu" signal "BOTTOM")
		(9 "F.Adhes" user "F.Adhesive")
		(11 "B.Adhes" user "B.Adhesive")
		(13 "F.Paste" user "Package Geometry/Pastemask Top")
		(15 "B.Paste" user "Package Geometry/Pastemask Bottom")
		(5 "F.SilkS" user "Ref Des/Silkscreen Top")
		(7 "B.SilkS" user "Ref Des/Silkscreen Bottom")
		(1 "F.Mask" user "Board Geometry/Soldermask Top")
		(3 "B.Mask" user "Board Geometry/Soldermask Bottom")
		(17 "Dwgs.User" user "User.Drawings")
		(19 "Cmts.User" user "User.Comments")
		(21 "Eco1.User" user "User.Eco1")
		(23 "Eco2.User" user "User.Eco2")
		(25 "Edge.Cuts" user "Board Geometry/Outline")
		(27 "Margin" user)
		(31 "F.CrtYd" user "Package Geometry/Place Bound Top")
		(29 "B.CrtYd" user "Package Geometry/Place Bound Bottom")
		(35 "F.Fab" user "Ref Des/Assembly Top")
		(33 "B.Fab" user "Ref Des/Assembly Bottom")
	)
	(footprint ""
		(layer "F.Cu")
		(at 15.58417 -70.194678)
		(property "Reference" "R3142"
			(at 0 0 0)
			(layer "F.SilkS")
			(hide yes)
			(effects
				(font
					(size 1.27 1.27)
				)
			)
		)
		(property "Value" ""
			(at 0 0 0)
			(layer "F.Fab")
			(effects
				(font
					(size 1.27 1.27)
				)
			)
		)
		(duplicate_pad_numbers_are_jumpers no)
		(fp_line
			(start -0.7874 -0.4064)
			(end 0.7874 -0.4064)
			(stroke
				(width 0.1524)
				(type default)
			)
			(layer "F.SilkS")
		)
		(fp_line
			(start -0.7874 0.4064)
			(end -0.7874 -0.4064)
			(stroke
				(width 0.1524)
				(type default)
			)
			(layer "F.SilkS")
		)
		(fp_line
			(start 0.7874 -0.4064)
			(end 0.7874 0.4064)
			(stroke
				(width 0.1524)
				(type default)
			)
			(layer "F.SilkS")
		)
		(fp_line
			(start 0.7874 0.4064)
			(end -0.7874 0.4064)
			(stroke
				(width 0.1524)
				(type default)
			)
			(layer "F.SilkS")
		)
		(fp_line
			(start -0.67945 -0.305054)
			(end -0.12065 -0.305054)
			(stroke
				(width 0.1)
				(type default)
			)
			(layer "F.Fab")
		)
		(fp_line
			(start -0.67945 0.3048)
			(end -0.67945 -0.305054)
			(stroke
				(width 0.1)
				(type default)
			)
			(layer "F.Fab")
		)
		(fp_line
			(start -0.12065 -0.305054)
			(end -0.12065 -0.2794)
			(stroke
				(width 0.1)
				(type default)
			)
			(layer "F.Fab")
		)
		(fp_line
			(start -0.12065 -0.2794)
			(end 0.12065 -0.2794)
			(stroke
				(width 0.1)
				(type default)
			)
			(layer "F.Fab")
		)
		(fp_line
			(start -0.12065 0.2794)
			(end -0.12065 0.3048)
			(stroke
				(width 0.1)
				(type default)
			)
			(layer "F.Fab")
		)
		(fp_line
			(start -0.12065 0.3048)
			(end -0.67945 0.3048)
			(stroke
				(width 0.1)
				(type default)
			)
			(layer "F.Fab")
		)
		(fp_line
			(start 0.120396 0.2794)
			(end -0.12065 0.2794)
			(stroke
				(width 0.1)
				(type default)
			)
			(layer "F.Fab")
		)
		(fp_line
			(start 0.120396 0.3048)
			(end 0.120396 0.2794)
			(stroke
				(width 0.1)
				(type default)
			)
			(layer "F.Fab")
		)
		(fp_line
			(start 0.12065 -0.3048)
			(end 0.67945 -0.3048)
			(stroke
				(width 0.1)
				(type default)
			)
			(layer "F.Fab")
		)
		(fp_line
			(start 0.12065 -0.2794)
			(end 0.12065 -0.3048)
			(stroke
				(width 0.1)
				(type default)
			)
			(layer "F.Fab")
		)
		(fp_line
			(start 0.67945 -0.3048)
			(end 0.67945 0.3048)
			(stroke
				(width 0.1)
				(type default)
			)
			(layer "F.Fab")
		)
		(fp_line
			(start 0.67945 0.3048)
			(end 0.120396 0.3048)
			(stroke
				(width 0.1)
				(type default)
			)
			(layer "F.Fab")
		)
		(pad "1" smd circle
			(at -0.40005 0)
			(size 0 0)
			(layers "F.Cu" "F.Mask" "F.Paste")
			(net "HP_LVC3_OCP_V3_2_PRSNT2_N_R")
		)
		(pad "2" smd circle
			(at 0.40005 0)
			(size 0 0)
			(layers "F.Cu" "F.Mask" "F.Paste")
			(net "HP_LVC3_OCP_V3_2_PRSNT2_PLD_N")
		)
	)
	(footprint ""
		(layer "F.Cu")
		(at 17.432782 -414.120584 180)
		(property "Reference" "PC6600"
			(at 0 0 180)
			(layer "F.SilkS")
			(hide yes)
			(effects
				(font
					(size 1.27 1.27)
				)
			)
		)
		(property "Value" ""
			(at 0 0 180)
			(layer "F.Fab")
			(effects
				(font
					(size 1.27 1.27)
				)
			)
		)
		(duplicate_pad_numbers_are_jumpers no)
		(fp_line
			(start 0.7874 0.4064)
			(end -0.7874 0.4064)
			(stroke
				(width 0.1524)
				(type default)
			)
			(layer "F.SilkS")
		)
		(fp_line
			(start 0.7874 -0.4064)
			(end 0.7874 0.4064)
			(stroke
				(width 0.1524)
				(type default)
			)
			(layer "F.SilkS")
		)
		(fp_line
			(start -0.7874 0.4064)
			(end -0.7874 -0.4064)
			(stroke
				(width 0.1524)
				(type default)
			)
			(layer "F.SilkS")
		)
		(fp_line
			(start -0.7874 -0.4064)
			(end 0.7874 -0.4064)
			(stroke
				(width 0.1524)
				(type default)
			)
			(layer "F.SilkS")
		)
		(fp_line
			(start 0.67945 0.3048)
			(end 0.120396 0.3048)
			(stroke
				(width 0.1)
				(type default)
			)
			(layer "F.Fab")
		)
		(fp_line
			(start 0.67945 -0.3048)
			(end 0.67945 0.3048)
			(stroke
				(width 0.1)
				(type default)
			)
			(layer "F.Fab")
		)
		(fp_line
			(start 0.12065 -0.2794)
			(end 0.12065 -0.3048)
			(stroke
				(width 0.1)
				(type default)
			)
			(layer "F.Fab")
		)
		(fp_line
			(start 0.12065 -0.3048)
			(end 0.67945 -0.3048)
			(stroke
				(width 0.1)
				(type default)
			)
			(layer "F.Fab")
		)
		(fp_line
			(start 0.120396 0.3048)
			(end 0.120396 0.2794)
			(stroke
				(width 0.1)
				(type default)
			)
			(layer "F.Fab")
		)
		(fp_line
			(start 0.120396 0.2794)
			(end -0.12065 0.2794)
			(stroke
				(width 0.1)
				(type default)
			)
			(layer "F.Fab")
		)
		(fp_line
			(start -0.12065 0.3048)
			(end -0.67945 0.3048)
			(stroke
				(width 0.1)
				(type default)
			)
			(layer "F.Fab")
		)
		(fp_line
			(start -0.12065 0.2794)
			(end -0.12065 0.3048)
			(stroke
				(width 0.1)
				(type default)
			)
			(layer "F.Fab")
		)
		(fp_line
			(start -0.12065 -0.2794)
			(end 0.12065 -0.2794)
			(stroke
				(width 0.1)
				(type default)
			)
			(layer "F.Fab")
		)
		(fp_line
			(start -0.12065 -0.305054)
			(end -0.12065 -0.2794)
			(stroke
				(width 0.1)
				(type default)
			)
			(layer "F.Fab")
		)
		(fp_line
			(start -0.67945 0.3048)
			(end -0.67945 -0.305054)
			(stroke
				(width 0.1)
				(type default)
			)
			(layer "F.Fab")
		)
		(fp_line
			(start -0.67945 -0.305054)
			(end -0.12065 -0.305054)
			(stroke
				(width 0.1)
				(type default)
			)
			(layer "F.Fab")
		)
		(pad "1" smd circle
			(at -0.40005 0 180)
			(size 0 0)
			(layers "F.Cu" "F.Mask" "F.Paste")
			(net "P0V9_RETIMER_CPU1_SENSE_R_P")
		)
		(pad "2" smd circle
			(at 0.40005 0 180)
			(size 0 0)
			(layers "F.Cu" "F.Mask" "F.Paste")
			(net "P0V9_RETIMER_CPU1_SENSE_SH_N")
		)
	)
	(footprint ""
		(layer "F.Cu")
		(at 458.346302 -405.972264)
		(property "Reference" "PC6581_2"
			(at 0 0 0)
			(layer "F.SilkS")
			(hide yes)
			(effects
				(font
					(size 1.27 1.27)
				)
			)
		)
		(property "Value" ""
			(at 0 0 0)
			(layer "F.Fab")
			(effects
				(font
					(size 1.27 1.27)
				)
			)
		)
		(duplicate_pad_numbers_are_jumpers no)
		(fp_line
			(start -1.524 -0.762)
			(end 1.524 -0.762)
			(stroke
				(width 0.1524)
				(type default)
			)
			(layer "F.SilkS")
		)
		(fp_line
			(start -1.524 0.762)
			(end -1.524 -0.762)
			(stroke
				(width 0.1524)
				(type default)
			)
			(layer "F.SilkS")
		)
		(fp_line
			(start 1.524 -0.762)
			(end 1.524 0.762)
			(stroke
				(width 0.1524)
				(type default)
			)
			(layer "F.SilkS")
		)
		(fp_line
			(start 1.524 0.762)
			(end -1.524 0.762)
			(stroke
				(width 0.1524)
				(type default)
			)
			(layer "F.SilkS")
		)
		(fp_line
			(start -1.1049 -0.724916)
			(end -1.1049 0.724916)
			(stroke
				(width 0.1)
				(type default)
			)
			(layer "F.Fab")
		)
		(fp_line
			(start -1.1049 0.724916)
			(end 1.1049 0.724916)
			(stroke
				(width 0.1)
				(type default)
			)
			(layer "F.Fab")
		)
		(fp_line
			(start 1.1049 -0.724916)
			(end -1.1049 -0.724916)
			(stroke
				(width 0.1)
				(type default)
			)
			(layer "F.Fab")
		)
		(fp_line
			(start 1.1049 0.724916)
			(end 1.1049 -0.724916)
			(stroke
				(width 0.1)
				(type default)
			)
			(layer "F.Fab")
		)
		(pad "1" smd rect
			(at -0.889 0 180)
			(size 1.016 1.27)
			(layers "F.Cu" "F.Mask" "F.Paste")
			(net "SW_P12V_AUX_P0V9_RETIMER_CPU0_FLT")
		)
		(pad "2" smd rect
			(at 0.889 0 180)
			(size 1.016 1.27)
			(layers "F.Cu" "F.Mask" "F.Paste")
			(net "GND")
		)
	)
)
